# S9S_MB_2U (Grand Teton) — schematic netlist excerpt (pin names and nets, part order shuffled) for the footprints in the layout excerpt that follows; sources: Cadence DE-HDL packaged netlist, KiCad conversion of 03242023_DA0F0TMBIJ0_F0T_Motherboard_J_brd_V01_OCP.brd

C1202  Q_CAP  22UF 4V 20% X6S  pkg C0603  page 189 : A = P1V8_PCH_AUX ; B = GND
PR2518  Q_RES  10 1% EMPTY  pkg 0402LF  page 304 : A = P12V_HSC_ADC_N ; B = P12V_HSC_SENSE2_R4_N

(kicad_pcb
	(version 20260206)
	(generator "pcbnew")
	(generator_version "10.0")
	(general
		(thickness 1.6)
		(legacy_teardrops no)
	)
	(paper "A4")
	(title_block
		(title "03242023_DA0F0TMBIJ0_F0T_Motherboard_J_brd_V01_OCP.brd")
		(comment 1 "Grand Teton / footprints 4763-4764 of 6105")
	)
	(layers
		(0 "F.Cu" signal "TOP")
		(4 "In1.Cu" signal "GND")
		(6 "In2.Cu" signal "IN1")
		(8 "In3.Cu" signal "GND1")
		(10 "In4.Cu" signal "IN2")
		(12 "In5.Cu" signal "GND2")
		(14 "In6.Cu" signal "IN3")
		(16 "In7.Cu" signal "GND3")
		(18 "In8.Cu" signal "VCC")
		(20 "In9.Cu" signal "VCC1")
		(22 "In10.Cu" signal "GND4")
		(24 "In11.Cu" signal "IN4")
		(26 "In12.Cu" signal "GND5")
		(28 "In13.Cu" signal "IN5")
		(30 "In14.Cu" signal "GND6")
		(32 "In15.Cu" signal "IN6")
		(34 "In16.Cu" signal "GND7")
		(2 "B.Cu" signal "BOTTOM")
		(9 "F.Adhes" user "F.Adhesive")
		(11 "B.Adhes" user "B.Adhesive")
		(13 "F.Paste" user "Package Geometry/Pastemask Top")
		(15 "B.Paste" user "Package Geometry/Pastemask Bottom")
		(5 "F.SilkS" user "Ref Des/Silkscreen Top")
		(7 "B.SilkS" user "Ref Des/Silkscreen Bottom")
		(1 "F.Mask" user "Board Geometry/Soldermask Top")
		(3 "B.Mask" user "Board Geometry/Soldermask Bottom")
		(17 "Dwgs.User" user "User.Drawings")
		(19 "Cmts.User" user "User.Comments")
		(21 "Eco1.User" user "User.Eco1")
		(23 "Eco2.User" user "User.Eco2")
		(25 "Edge.Cuts" user "Board Geometry/Outline")
		(27 "Margin" user)
		(31 "F.CrtYd" user "Package Geometry/Place Bound Top")
		(29 "B.CrtYd" user "Package Geometry/Place Bound Bottom")
		(35 "F.Fab" user "Ref Des/Assembly Top")
		(33 "B.Fab" user "Ref Des/Assembly Bottom")
	)
	(footprint ""
		(layer "B.Cu")
		(at 336.269584 -58.486548 -90)
		(property "Reference" "C1202"
			(at 0 0 90)
			(layer "B.SilkS")
			(hide yes)
			(effects
				(font
					(size 1.27 1.27)
				)
				(justify mirror)
			)
		)
		(property "Value" ""
			(at 0 0 90)
			(layer "B.Fab")
			(effects
				(font
					(size 1.27 1.27)
				)
				(justify mirror)
			)
		)
		(duplicate_pad_numbers_are_jumpers no)
		(fp_line
			(start -1.2954 0.5842)
			(end 1.2954 0.5842)
			(stroke
				(width 0.1524)
				(type default)
			)
			(layer "B.SilkS")
		)
		(fp_line
			(start 1.2954 0.5842)
			(end 1.2954 -0.5842)
			(stroke
				(width 0.1524)
				(type default)
			)
			(layer "B.SilkS")
		)
		(fp_line
			(start -1.2954 -0.5842)
			(end -1.2954 0.5842)
			(stroke
				(width 0.1524)
				(type default)
			)
			(layer "B.SilkS")
		)
		(fp_line
			(start 0 -0.5842)
			(end 0 0.5842)
			(stroke
				(width 0.1524)
				(type default)
			)
			(layer "B.SilkS")
		)
		(fp_line
			(start 1.2954 -0.5842)
			(end -1.2954 -0.5842)
			(stroke
				(width 0.1524)
				(type default)
			)
			(layer "B.SilkS")
		)
		(fp_line
			(start -0.8636 0.4572)
			(end 0.8636 0.4572)
			(stroke
				(width 0.1)
				(type default)
			)
			(layer "B.Fab")
		)
		(fp_line
			(start 0.8636 0.4572)
			(end 0.8636 0.4064)
			(stroke
				(width 0.1)
				(type default)
			)
			(layer "B.Fab")
		)
		(fp_line
			(start -1.1938 0.4064)
			(end -0.8636 0.4064)
			(stroke
				(width 0.1)
				(type default)
			)
			(layer "B.Fab")
		)
		(fp_line
			(start -0.8636 0.4064)
			(end -0.8636 0.4572)
			(stroke
				(width 0.1)
				(type default)
			)
			(layer "B.Fab")
		)
		(fp_line
			(start 0.8636 0.4064)
			(end 1.1938 0.4064)
			(stroke
				(width 0.1)
				(type default)
			)
			(layer "B.Fab")
		)
		(fp_line
			(start 1.1938 0.4064)
			(end 1.1938 -0.4064)
			(stroke
				(width 0.1)
				(type default)
			)
			(layer "B.Fab")
		)
		(fp_line
			(start -1.1938 -0.4064)
			(end -1.1938 0.4064)
			(stroke
				(width 0.1)
				(type default)
			)
			(layer "B.Fab")
		)
		(fp_line
			(start -0.8636 -0.4064)
			(end -1.1938 -0.4064)
			(stroke
				(width 0.1)
				(type default)
			)
			(layer "B.Fab")
		)
		(fp_line
			(start 0.8636 -0.4064)
			(end 0.8636 -0.4572)
			(stroke
				(width 0.1)
				(type default)
			)
			(layer "B.Fab")
		)
		(fp_line
			(start 1.1938 -0.4064)
			(end 0.8636 -0.4064)
			(stroke
				(width 0.1)
				(type default)
			)
			(layer "B.Fab")
		)
		(fp_line
			(start -0.8636 -0.4572)
			(end -0.8636 -0.4064)
			(stroke
				(width 0.1)
				(type default)
			)
			(layer "B.Fab")
		)
		(fp_line
			(start 0.8636 -0.4572)
			(end -0.8636 -0.4572)
			(stroke
				(width 0.1)
				(type default)
			)
			(layer "B.Fab")
		)
		(pad "1" smd rect
			(at 0.7366 0 180)
			(size 0.7112 0.8128)
			(layers "B.Cu" "B.Mask" "B.Paste")
			(net "P1V8_PCH_AUX")
		)
		(pad "2" smd rect
			(at -0.7366 0 180)
			(size 0.7112 0.8128)
			(layers "B.Cu" "B.Mask" "B.Paste")
			(net "GND")
		)
	)
	(footprint ""
		(layer "B.Cu")
		(at 292.528498 -403.031452 90)
		(property "Reference" "PR2518"
			(at 0 0 90)
			(layer "B.SilkS")
			(hide yes)
			(effects
				(font
					(size 1.27 1.27)
				)
				(justify mirror)
			)
		)
		(property "Value" ""
			(at 0 0 90)
			(layer "B.Fab")
			(effects
				(font
					(size 1.27 1.27)
				)
				(justify mirror)
			)
		)
		(duplicate_pad_numbers_are_jumpers no)
		(fp_line
			(start 0.7874 -0.4064)
			(end -0.7874 -0.4064)
			(stroke
				(width 0.1524)
				(type default)
			)
			(layer "B.SilkS")
		)
		(fp_line
			(start -0.7874 -0.4064)
			(end -0.7874 0.4064)
			(stroke
				(width 0.1524)
				(type default)
			)
			(layer "B.SilkS")
		)
		(fp_line
			(start 0.7874 0.4064)
			(end 0.7874 -0.4064)
			(stroke
				(width 0.1524)
				(type default)
			)
			(layer "B.SilkS")
		)
		(fp_line
			(start -0.7874 0.4064)
			(end 0.7874 0.4064)
			(stroke
				(width 0.1524)
				(type default)
			)
			(layer "B.SilkS")
		)
		(fp_line
			(start 0.67945 -0.305054)
			(end 0.12065 -0.305054)
			(stroke
				(width 0.1)
				(type default)
			)
			(layer "B.Fab")
		)
		(fp_line
			(start 0.12065 -0.305054)
			(end 0.12065 -0.2794)
			(stroke
				(width 0.1)
				(type default)
			)
			(layer "B.Fab")
		)
		(fp_line
			(start -0.12065 -0.3048)
			(end -0.67945 -0.3048)
			(stroke
				(width 0.1)
				(type default)
			)
			(layer "B.Fab")
		)
		(fp_line
			(start -0.67945 -0.3048)
			(end -0.67945 0.3048)
			(stroke
				(width 0.1)
				(type default)
			)
			(layer "B.Fab")
		)
		(fp_line
			(start 0.12065 -0.2794)
			(end -0.12065 -0.2794)
			(stroke
				(width 0.1)
				(type default)
			)
			(layer "B.Fab")
		)
		(fp_line
			(start -0.12065 -0.2794)
			(end -0.12065 -0.3048)
			(stroke
				(width 0.1)
				(type default)
			)
			(layer "B.Fab")
		)
		(fp_line
			(start 0.12065 0.2794)
			(end 0.12065 0.3048)
			(stroke
				(width 0.1)
				(type default)
			)
			(layer "B.Fab")
		)
		(fp_line
			(start -0.120396 0.2794)
			(end 0.12065 0.2794)
			(stroke
				(width 0.1)
				(type default)
			)
			(layer "B.Fab")
		)
		(fp_line
			(start 0.67945 0.3048)
			(end 0.67945 -0.305054)
			(stroke
				(width 0.1)
				(type default)
			)
			(layer "B.Fab")
		)
		(fp_line
			(start 0.12065 0.3048)
			(end 0.67945 0.3048)
			(stroke
				(width 0.1)
				(type default)
			)
			(layer "B.Fab")
		)
		(fp_line
			(start -0.120396 0.3048)
			(end -0.120396 0.2794)
			(stroke
				(width 0.1)
				(type default)
			)
			(layer "B.Fab")
		)
		(fp_line
			(start -0.67945 0.3048)
			(end -0.120396 0.3048)
			(stroke
				(width 0.1)
				(type default)
			)
			(layer "B.Fab")
		)
		(pad "1" smd circle
			(at 0.40005 0 270)
			(size 0 0)
			(layers "B.Cu" "B.Mask" "B.Paste")
			(net "P12V_HSC_ADC_N")
		)
		(pad "2" smd circle
			(at -0.40005 0 270)
			(size 0 0)
			(layers "B.Cu" "B.Mask" "B.Paste")
			(net "P12V_HSC_SENSE2_R4_N")
		)
	)
)
